(kicad_pcb
	(version 20260206)
	(generator "pcbnew")
	(generator_version "10.0")
	(general
		(thickness 1.6)
		(legacy_teardrops no)
	)
	(paper "A4")
	(title_block
		(title "03242023_DA0F0TMBIJ0_F0T_Motherboard_J_brd_V01_OCP.brd")
		(comment 1 "Grand Teton / footprint 3553 of 6105 (J6), pads 113-224 of 291")
	)
	(layers
		(0 "F.Cu" signal "TOP")
		(4 "In1.Cu" signal "GND")
		(6 "In2.Cu" signal "IN1")
		(8 "In3.Cu" signal "GND1")
		(10 "In4.Cu" signal "IN2")
		(12 "In5.Cu" signal "GND2")
		(14 "In6.Cu" signal "IN3")
		(16 "In7.Cu" signal "GND3")
		(18 "In8.Cu" signal "VCC")
		(20 "In9.Cu" signal "VCC1")
		(22 "In10.Cu" signal "GND4")
		(24 "In11.Cu" signal "IN4")
		(26 "In12.Cu" signal "GND5")
		(28 "In13.Cu" signal "IN5")
		(30 "In14.Cu" signal "GND6")
		(32 "In15.Cu" signal "IN6")
		(34 "In16.Cu" signal "GND7")
		(2 "B.Cu" signal "BOTTOM")
		(9 "F.Adhes" user "F.Adhesive")
		(11 "B.Adhes" user "B.Adhesive")
		(13 "F.Paste" user "Package Geometry/Pastemask Top")
		(15 "B.Paste" user "Package Geometry/Pastemask Bottom")
		(5 "F.SilkS" user "Ref Des/Silkscreen Top")
		(7 "B.SilkS" user "Ref Des/Silkscreen Bottom")
		(1 "F.Mask" user "Board Geometry/Soldermask Top")
		(3 "B.Mask" user "Board Geometry/Soldermask Bottom")
		(17 "Dwgs.User" user "User.Drawings")
		(19 "Cmts.User" user "User.Comments")
		(21 "Eco1.User" user "User.Eco1")
		(23 "Eco2.User" user "User.Eco2")
		(25 "Edge.Cuts" user "Board Geometry/Outline")
		(27 "Margin" user)
		(31 "F.CrtYd" user "Package Geometry/Place Bound Top")
		(29 "B.CrtYd" user "Package Geometry/Place Bound Bottom")
		(35 "F.Fab" user "Ref Des/Assembly Top")
		(33 "B.Fab" user "Ref Des/Assembly Bottom")
	)
	(footprint ""
		(layer "F.Cu")
		(at 280.761948 -258.091686)
		(property "Reference" "J6"
			(at -3.683 -81.702148 0)
			(unlocked yes)
			(layer "F.SilkS")
			(effects
				(font
					(size 0.7874 0.5842)
					(thickness 0.1524)
				)
				(justify left)
			)
		)
		(property "Value" ""
			(at 0 0 0)
			(layer "F.Fab")
			(effects
				(font
					(size 1.27 1.27)
				)
			)
		)
		(duplicate_pad_numbers_are_jumpers no)
		(pad "113" smd rect
			(at -2.050034 36.975034 270)
			(size 0.519938 1.4986)
			(layers "F.Cu" "F.Mask" "F.Paste")
			(net "M_C_CPU0_SB_DQ<9>")
		)
		(pad "114" smd rect
			(at -2.050034 37.824918 270)
			(size 0.519938 1.4986)
			(layers "F.Cu" "F.Mask" "F.Paste")
			(net "GND")
		)
		(pad "115" smd rect
			(at -2.050034 38.675056 270)
			(size 0.519938 1.4986)
			(layers "F.Cu" "F.Mask" "F.Paste")
			(net "M_C_CPU0_SB_DQS_DP<1>")
		)
		(pad "116" smd rect
			(at -2.050034 39.52494 270)
			(size 0.519938 1.4986)
			(layers "F.Cu" "F.Mask" "F.Paste")
			(net "M_C_CPU0_SB_DQS_DN<1>")
		)
		(pad "117" smd rect
			(at -2.050034 40.375078 270)
			(size 0.519938 1.4986)
			(layers "F.Cu" "F.Mask" "F.Paste")
			(net "GND")
		)
		(pad "118" smd rect
			(at -2.050034 41.224962 270)
			(size 0.519938 1.4986)
			(layers "F.Cu" "F.Mask" "F.Paste")
			(net "M_C_CPU0_SB_DQ<12>")
		)
		(pad "119" smd rect
			(at -2.050034 42.0751 270)
			(size 0.519938 1.4986)
			(layers "F.Cu" "F.Mask" "F.Paste")
			(net "GND")
		)
		(pad "120" smd rect
			(at -2.050034 42.924984 270)
			(size 0.519938 1.4986)
			(layers "F.Cu" "F.Mask" "F.Paste")
			(net "M_C_CPU0_SB_DQ<13>")
		)
		(pad "121" smd rect
			(at -2.050034 43.775122 270)
			(size 0.519938 1.4986)
			(layers "F.Cu" "F.Mask" "F.Paste")
			(net "GND")
		)
		(pad "122" smd rect
			(at -2.050034 44.625006 270)
			(size 0.519938 1.4986)
			(layers "F.Cu" "F.Mask" "F.Paste")
			(net "M_C_CPU0_SB_DQ<16>")
		)
		(pad "123" smd rect
			(at -2.050034 45.47489 270)
			(size 0.519938 1.4986)
			(layers "F.Cu" "F.Mask" "F.Paste")
			(net "GND")
		)
		(pad "124" smd rect
			(at -2.050034 46.325028 270)
			(size 0.519938 1.4986)
			(layers "F.Cu" "F.Mask" "F.Paste")
			(net "M_C_CPU0_SB_DQ<17>")
		)
		(pad "125" smd rect
			(at -2.050034 47.174912 270)
			(size 0.519938 1.4986)
			(layers "F.Cu" "F.Mask" "F.Paste")
			(net "GND")
		)
		(pad "126" smd rect
			(at -2.050034 48.02505 270)
			(size 0.519938 1.4986)
			(layers "F.Cu" "F.Mask" "F.Paste")
			(net "M_C_CPU0_SB_DQS_DP<2>")
		)
		(pad "127" smd rect
			(at -2.050034 48.874934 270)
			(size 0.519938 1.4986)
			(layers "F.Cu" "F.Mask" "F.Paste")
			(net "M_C_CPU0_SB_DQS_DN<2>")
		)
		(pad "128" smd rect
			(at -2.050034 49.725072 270)
			(size 0.519938 1.4986)
			(layers "F.Cu" "F.Mask" "F.Paste")
			(net "GND")
		)
		(pad "129" smd rect
			(at -2.050034 50.574956 270)
			(size 0.519938 1.4986)
			(layers "F.Cu" "F.Mask" "F.Paste")
			(net "M_C_CPU0_SB_DQ<20>")
		)
		(pad "130" smd rect
			(at -2.050034 51.425094 270)
			(size 0.519938 1.4986)
			(layers "F.Cu" "F.Mask" "F.Paste")
			(net "GND")
		)
		(pad "131" smd rect
			(at -2.050034 52.274978 270)
			(size 0.519938 1.4986)
			(layers "F.Cu" "F.Mask" "F.Paste")
			(net "M_C_CPU0_SB_DQ<21>")
		)
		(pad "132" smd rect
			(at -2.050034 53.125116 270)
			(size 0.519938 1.4986)
			(layers "F.Cu" "F.Mask" "F.Paste")
			(net "GND")
		)
		(pad "133" smd rect
			(at -2.050034 53.975 270)
			(size 0.519938 1.4986)
			(layers "F.Cu" "F.Mask" "F.Paste")
			(net "M_C_CPU0_SB_DQ<24>")
		)
		(pad "134" smd rect
			(at -2.050034 54.824884 270)
			(size 0.519938 1.4986)
			(layers "F.Cu" "F.Mask" "F.Paste")
			(net "GND")
		)
		(pad "135" smd rect
			(at -2.050034 55.675022 270)
			(size 0.519938 1.4986)
			(layers "F.Cu" "F.Mask" "F.Paste")
			(net "M_C_CPU0_SB_DQ<25>")
		)
		(pad "136" smd rect
			(at -2.050034 56.524906 270)
			(size 0.519938 1.4986)
			(layers "F.Cu" "F.Mask" "F.Paste")
			(net "GND")
		)
		(pad "137" smd rect
			(at -2.050034 57.375044 270)
			(size 0.519938 1.4986)
			(layers "F.Cu" "F.Mask" "F.Paste")
			(net "M_C_CPU0_SB_DQS_DP<3>")
		)
		(pad "138" smd rect
			(at -2.050034 58.224928 270)
			(size 0.519938 1.4986)
			(layers "F.Cu" "F.Mask" "F.Paste")
			(net "M_C_CPU0_SB_DQS_DN<3>")
		)
		(pad "139" smd rect
			(at -2.050034 59.075066 270)
			(size 0.519938 1.4986)
			(layers "F.Cu" "F.Mask" "F.Paste")
			(net "GND")
		)
		(pad "140" smd rect
			(at -2.050034 59.92495 270)
			(size 0.519938 1.4986)
			(layers "F.Cu" "F.Mask" "F.Paste")
			(net "M_C_CPU0_SB_DQ<28>")
		)
		(pad "141" smd rect
			(at -2.050034 60.775088 270)
			(size 0.519938 1.4986)
			(layers "F.Cu" "F.Mask" "F.Paste")
			(net "GND")
		)
		(pad "142" smd rect
			(at -2.050034 61.624972 270)
			(size 0.519938 1.4986)
			(layers "F.Cu" "F.Mask" "F.Paste")
			(net "M_C_CPU0_SB_DQ<29>")
		)
		(pad "143" smd rect
			(at -2.050034 62.47511 270)
			(size 0.519938 1.4986)
			(layers "F.Cu" "F.Mask" "F.Paste")
			(net "GND")
		)
		(pad "144" smd rect
			(at -2.050034 63.324994 270)
			(size 0.519938 1.4986)
			(layers "F.Cu" "F.Mask" "F.Paste")
			(net "TP_CHC_CPU0_DIMM2_FRU_1")
		)
		(pad "145" smd rect
			(at 2.050034 -63.324994 270)
			(size 0.519938 1.4986)
			(layers "F.Cu" "F.Mask" "F.Paste")
			(net "P12V_S3_AUX_CPU0_NVDIMM")
		)
		(pad "146" smd rect
			(at 2.050034 -62.47511 270)
			(size 0.519938 1.4986)
			(layers "F.Cu" "F.Mask" "F.Paste")
			(net "P12V_S3_AUX_CPU0_NVDIMM")
		)
		(pad "147" smd rect
			(at 2.050034 -61.624972 270)
			(size 0.519938 1.4986)
			(layers "F.Cu" "F.Mask" "F.Paste")
			(net "PWRGD_CHC_CPU0_DIMM2")
		)
		(pad "148" smd rect
			(at 2.050034 -60.775088 270)
			(size 0.519938 1.4986)
			(layers "F.Cu" "F.Mask" "F.Paste")
			(net "PD_CHC_CPU0_DIMM2_SAA")
		)
		(pad "149" smd rect
			(at 2.050034 -59.92495 270)
			(size 0.519938 1.4986)
			(layers "F.Cu" "F.Mask" "F.Paste")
			(net "TP_CHC_CPU0_DIMM2_FRU_2")
		)
		(pad "150" smd rect
			(at 2.050034 -59.075066 270)
			(size 0.519938 1.4986)
			(layers "F.Cu" "F.Mask" "F.Paste")
			(net "TP_CHC_CPU0_DIMM2_FRU_3")
		)
		(pad "151" smd rect
			(at 2.050034 -58.224928 270)
			(size 0.519938 1.4986)
			(layers "F.Cu" "F.Mask" "F.Paste")
			(net "GND")
		)
		(pad "152" smd rect
			(at 2.050034 -57.375044 270)
			(size 0.519938 1.4986)
			(layers "F.Cu" "F.Mask" "F.Paste")
			(net "M_C_CPU0_SA_DQ<2>")
		)
		(pad "153" smd rect
			(at 2.050034 -56.524906 270)
			(size 0.519938 1.4986)
			(layers "F.Cu" "F.Mask" "F.Paste")
			(net "GND")
		)
		(pad "154" smd rect
			(at 2.050034 -55.675022 270)
			(size 0.519938 1.4986)
			(layers "F.Cu" "F.Mask" "F.Paste")
			(net "M_C_CPU0_SA_DQ<3>")
		)
		(pad "155" smd rect
			(at 2.050034 -54.824884 270)
			(size 0.519938 1.4986)
			(layers "F.Cu" "F.Mask" "F.Paste")
			(net "GND")
		)
		(pad "156" smd rect
			(at 2.050034 -53.975 270)
			(size 0.519938 1.4986)
			(layers "F.Cu" "F.Mask" "F.Paste")
			(net "M_C_CPU0_SA_DQS_DN<5>")
		)
		(pad "157" smd rect
			(at 2.050034 -53.125116 270)
			(size 0.519938 1.4986)
			(layers "F.Cu" "F.Mask" "F.Paste")
			(net "M_C_CPU0_SA_DQS_DP<5>")
		)
		(pad "158" smd rect
			(at 2.050034 -52.274978 270)
			(size 0.519938 1.4986)
			(layers "F.Cu" "F.Mask" "F.Paste")
			(net "GND")
		)
		(pad "159" smd rect
			(at 2.050034 -51.425094 270)
			(size 0.519938 1.4986)
			(layers "F.Cu" "F.Mask" "F.Paste")
			(net "M_C_CPU0_SA_DQ<6>")
		)
		(pad "160" smd rect
			(at 2.050034 -50.574956 270)
			(size 0.519938 1.4986)
			(layers "F.Cu" "F.Mask" "F.Paste")
			(net "GND")
		)
		(pad "161" smd rect
			(at 2.050034 -49.725072 270)
			(size 0.519938 1.4986)
			(layers "F.Cu" "F.Mask" "F.Paste")
			(net "M_C_CPU0_SA_DQ<7>")
		)
		(pad "162" smd rect
			(at 2.050034 -48.874934 270)
			(size 0.519938 1.4986)
			(layers "F.Cu" "F.Mask" "F.Paste")
			(net "GND")
		)
		(pad "163" smd rect
			(at 2.050034 -48.02505 270)
			(size 0.519938 1.4986)
			(layers "F.Cu" "F.Mask" "F.Paste")
			(net "M_C_CPU0_SA_DQ<10>")
		)
		(pad "164" smd rect
			(at 2.050034 -47.174912 270)
			(size 0.519938 1.4986)
			(layers "F.Cu" "F.Mask" "F.Paste")
			(net "GND")
		)
		(pad "165" smd rect
			(at 2.050034 -46.325028 270)
			(size 0.519938 1.4986)
			(layers "F.Cu" "F.Mask" "F.Paste")
			(net "M_C_CPU0_SA_DQ<11>")
		)
		(pad "166" smd rect
			(at 2.050034 -45.47489 270)
			(size 0.519938 1.4986)
			(layers "F.Cu" "F.Mask" "F.Paste")
			(net "GND")
		)
		(pad "167" smd rect
			(at 2.050034 -44.625006 270)
			(size 0.519938 1.4986)
			(layers "F.Cu" "F.Mask" "F.Paste")
			(net "M_C_CPU0_SA_DQS_DN<6>")
		)
		(pad "168" smd rect
			(at 2.050034 -43.775122 270)
			(size 0.519938 1.4986)
			(layers "F.Cu" "F.Mask" "F.Paste")
			(net "M_C_CPU0_SA_DQS_DP<6>")
		)
		(pad "169" smd rect
			(at 2.050034 -42.924984 270)
			(size 0.519938 1.4986)
			(layers "F.Cu" "F.Mask" "F.Paste")
			(net "GND")
		)
		(pad "170" smd rect
			(at 2.050034 -42.0751 270)
			(size 0.519938 1.4986)
			(layers "F.Cu" "F.Mask" "F.Paste")
			(net "M_C_CPU0_SA_DQ<14>")
		)
		(pad "171" smd rect
			(at 2.050034 -41.224962 270)
			(size 0.519938 1.4986)
			(layers "F.Cu" "F.Mask" "F.Paste")
			(net "GND")
		)
		(pad "172" smd rect
			(at 2.050034 -40.375078 270)
			(size 0.519938 1.4986)
			(layers "F.Cu" "F.Mask" "F.Paste")
			(net "M_C_CPU0_SA_DQ<15>")
		)
		(pad "173" smd rect
			(at 2.050034 -39.52494 270)
			(size 0.519938 1.4986)
			(layers "F.Cu" "F.Mask" "F.Paste")
			(net "GND")
		)
		(pad "174" smd rect
			(at 2.050034 -38.675056 270)
			(size 0.519938 1.4986)
			(layers "F.Cu" "F.Mask" "F.Paste")
			(net "M_C_CPU0_SA_DQ<18>")
		)
		(pad "175" smd rect
			(at 2.050034 -37.824918 270)
			(size 0.519938 1.4986)
			(layers "F.Cu" "F.Mask" "F.Paste")
			(net "GND")
		)
		(pad "176" smd rect
			(at 2.050034 -36.975034 270)
			(size 0.519938 1.4986)
			(layers "F.Cu" "F.Mask" "F.Paste")
			(net "M_C_CPU0_SA_DQ<19>")
		)
		(pad "177" smd rect
			(at 2.050034 -36.124896 270)
			(size 0.519938 1.4986)
			(layers "F.Cu" "F.Mask" "F.Paste")
			(net "GND")
		)
		(pad "178" smd rect
			(at 2.050034 -35.275012 270)
			(size 0.519938 1.4986)
			(layers "F.Cu" "F.Mask" "F.Paste")
			(net "M_C_CPU0_SA_DQS_DN<7>")
		)
		(pad "179" smd rect
			(at 2.050034 -34.425128 270)
			(size 0.519938 1.4986)
			(layers "F.Cu" "F.Mask" "F.Paste")
			(net "M_C_CPU0_SA_DQS_DP<7>")
		)
		(pad "180" smd rect
			(at 2.050034 -33.57499 270)
			(size 0.519938 1.4986)
			(layers "F.Cu" "F.Mask" "F.Paste")
			(net "GND")
		)
		(pad "181" smd rect
			(at 2.050034 -32.725106 270)
			(size 0.519938 1.4986)
			(layers "F.Cu" "F.Mask" "F.Paste")
			(net "M_C_CPU0_SA_DQ<22>")
		)
		(pad "182" smd rect
			(at 2.050034 -31.874968 270)
			(size 0.519938 1.4986)
			(layers "F.Cu" "F.Mask" "F.Paste")
			(net "GND")
		)
		(pad "183" smd rect
			(at 2.050034 -31.025084 270)
			(size 0.519938 1.4986)
			(layers "F.Cu" "F.Mask" "F.Paste")
			(net "M_C_CPU0_SA_DQ<23>")
		)
		(pad "184" smd rect
			(at 2.050034 -30.174946 270)
			(size 0.519938 1.4986)
			(layers "F.Cu" "F.Mask" "F.Paste")
			(net "GND")
		)
		(pad "185" smd rect
			(at 2.050034 -29.325062 270)
			(size 0.519938 1.4986)
			(layers "F.Cu" "F.Mask" "F.Paste")
			(net "M_C_CPU0_SA_DQ<26>")
		)
		(pad "186" smd rect
			(at 2.050034 -28.474924 270)
			(size 0.519938 1.4986)
			(layers "F.Cu" "F.Mask" "F.Paste")
			(net "GND")
		)
		(pad "187" smd rect
			(at 2.050034 -27.62504 270)
			(size 0.519938 1.4986)
			(layers "F.Cu" "F.Mask" "F.Paste")
			(net "M_C_CPU0_SA_DQ<27>")
		)
		(pad "188" smd rect
			(at 2.050034 -26.774902 270)
			(size 0.519938 1.4986)
			(layers "F.Cu" "F.Mask" "F.Paste")
			(net "GND")
		)
		(pad "189" smd rect
			(at 2.050034 -25.925018 270)
			(size 0.519938 1.4986)
			(layers "F.Cu" "F.Mask" "F.Paste")
			(net "M_C_CPU0_SA_DQS_DN<8>")
		)
		(pad "190" smd rect
			(at 2.050034 -25.07488 270)
			(size 0.519938 1.4986)
			(layers "F.Cu" "F.Mask" "F.Paste")
			(net "M_C_CPU0_SA_DQS_DP<8>")
		)
		(pad "191" smd rect
			(at 2.050034 -24.224996 270)
			(size 0.519938 1.4986)
			(layers "F.Cu" "F.Mask" "F.Paste")
			(net "GND")
		)
		(pad "192" smd rect
			(at 2.050034 -23.375112 270)
			(size 0.519938 1.4986)
			(layers "F.Cu" "F.Mask" "F.Paste")
			(net "M_C_CPU0_SA_DQ<30>")
		)
		(pad "193" smd rect
			(at 2.050034 -22.524974 270)
			(size 0.519938 1.4986)
			(layers "F.Cu" "F.Mask" "F.Paste")
			(net "GND")
		)
		(pad "194" smd rect
			(at 2.050034 -21.67509 270)
			(size 0.519938 1.4986)
			(layers "F.Cu" "F.Mask" "F.Paste")
			(net "M_C_CPU0_SA_DQ<31>")
		)
		(pad "195" smd rect
			(at 2.050034 -20.824952 270)
			(size 0.519938 1.4986)
			(layers "F.Cu" "F.Mask" "F.Paste")
			(net "GND")
		)
		(pad "196" smd rect
			(at 2.050034 -19.975068 270)
			(size 0.519938 1.4986)
			(layers "F.Cu" "F.Mask" "F.Paste")
			(net "M_C_CPU0_SA_CB<2>")
		)
		(pad "197" smd rect
			(at 2.050034 -19.12493 270)
			(size 0.519938 1.4986)
			(layers "F.Cu" "F.Mask" "F.Paste")
			(net "GND")
		)
		(pad "198" smd rect
			(at 2.050034 -18.275046 270)
			(size 0.519938 1.4986)
			(layers "F.Cu" "F.Mask" "F.Paste")
			(net "M_C_CPU0_SA_CB<3>")
		)
		(pad "199" smd rect
			(at 2.050034 -17.424908 270)
			(size 0.519938 1.4986)
			(layers "F.Cu" "F.Mask" "F.Paste")
			(net "GND")
		)
		(pad "200" smd rect
			(at 2.050034 -16.575024 270)
			(size 0.519938 1.4986)
			(layers "F.Cu" "F.Mask" "F.Paste")
			(net "M_C_CPU0_SA_DQS_DN<9>")
		)
		(pad "201" smd rect
			(at 2.050034 -15.724886 270)
			(size 0.519938 1.4986)
			(layers "F.Cu" "F.Mask" "F.Paste")
			(net "M_C_CPU0_SA_DQS_DP<9>")
		)
		(pad "202" smd rect
			(at 2.050034 -14.875002 270)
			(size 0.519938 1.4986)
			(layers "F.Cu" "F.Mask" "F.Paste")
			(net "GND")
		)
		(pad "203" smd rect
			(at 2.050034 -14.025118 270)
			(size 0.519938 1.4986)
			(layers "F.Cu" "F.Mask" "F.Paste")
			(net "M_C_CPU0_SA_CB<6>")
		)
		(pad "204" smd rect
			(at 2.050034 -13.17498 270)
			(size 0.519938 1.4986)
			(layers "F.Cu" "F.Mask" "F.Paste")
			(net "GND")
		)
		(pad "205" smd rect
			(at 2.050034 -12.325096 270)
			(size 0.519938 1.4986)
			(layers "F.Cu" "F.Mask" "F.Paste")
			(net "M_C_CPU0_SA_CB<7>")
		)
		(pad "206" smd rect
			(at 2.050034 -11.474958 270)
			(size 0.519938 1.4986)
			(layers "F.Cu" "F.Mask" "F.Paste")
			(net "GND")
		)
		(pad "207" smd rect
			(at 2.050034 -10.625074 270)
			(size 0.519938 1.4986)
			(layers "F.Cu" "F.Mask" "F.Paste")
			(net "RST_M_CD_CPU0_FPGA_N")
		)
		(pad "208" smd rect
			(at 2.050034 -9.774936 270)
			(size 0.519938 1.4986)
			(layers "F.Cu" "F.Mask" "F.Paste")
			(net "GND")
		)
		(pad "209" smd rect
			(at 2.050034 -8.925052 270)
			(size 0.519938 1.4986)
			(layers "F.Cu" "F.Mask" "F.Paste")
			(net "M_C_CPU0_SA_CS_N<3>")
		)
		(pad "210" smd rect
			(at 2.050034 -8.074914 270)
			(size 0.519938 1.4986)
			(layers "F.Cu" "F.Mask" "F.Paste")
			(net "GND")
		)
		(pad "211" smd rect
			(at 2.050034 -7.22503 270)
			(size 0.519938 1.4986)
			(layers "F.Cu" "F.Mask" "F.Paste")
			(net "M_C_CPU0_SA_CA<1>")
		)
		(pad "212" smd rect
			(at 2.050034 -6.374892 270)
			(size 0.519938 1.4986)
			(layers "F.Cu" "F.Mask" "F.Paste")
			(net "GND")
		)
		(pad "213" smd rect
			(at 2.050034 -5.525008 270)
			(size 0.519938 1.4986)
			(layers "F.Cu" "F.Mask" "F.Paste")
			(net "M_C_CPU0_SA_CA<3>")
		)
		(pad "214" smd rect
			(at 2.050034 -4.675124 270)
			(size 0.519938 1.4986)
			(layers "F.Cu" "F.Mask" "F.Paste")
			(net "GND")
		)
		(pad "215" smd rect
			(at 2.050034 -3.824986 270)
			(size 0.519938 1.4986)
			(layers "F.Cu" "F.Mask" "F.Paste")
			(net "M_C_CPU0_SA_CA<5>")
		)
		(pad "216" smd rect
			(at 2.050034 -2.975102 270)
			(size 0.519938 1.4986)
			(layers "F.Cu" "F.Mask" "F.Paste")
			(net "GND")
		)
		(pad "217" smd rect
			(at 2.050034 -2.124964 270)
			(size 0.519938 1.4986)
			(layers "F.Cu" "F.Mask" "F.Paste")
			(net "M_C_CPU0_CLK_DP<1>")
		)
		(pad "218" smd rect
			(at 2.050034 -1.27508 270)
			(size 0.519938 1.4986)
			(layers "F.Cu" "F.Mask" "F.Paste")
			(net "M_C_CPU0_CLK_DN<1>")
		)
		(pad "219" smd rect
			(at 2.050034 -0.424942 270)
			(size 0.519938 1.4986)
			(layers "F.Cu" "F.Mask" "F.Paste")
			(net "GND")
		)
		(pad "220" smd rect
			(at 2.050034 5.525008 270)
			(size 0.519938 1.4986)
			(layers "F.Cu" "F.Mask" "F.Paste")
			(net "TP_CHC_CPU0_DIMM2_FRU_4")
		)
		(pad "221" smd rect
			(at 2.050034 6.374892 270)
			(size 0.519938 1.4986)
			(layers "F.Cu" "F.Mask" "F.Paste")
			(net "M_C_CPU0_SB_CA<1>")
		)
		(pad "222" smd rect
			(at 2.050034 7.22503 270)
			(size 0.519938 1.4986)
			(layers "F.Cu" "F.Mask" "F.Paste")
			(net "GND")
		)
		(pad "223" smd rect
			(at 2.050034 8.074914 270)
			(size 0.519938 1.4986)
			(layers "F.Cu" "F.Mask" "F.Paste")
			(net "M_C_CPU0_SB_CA<3>")
		)
		(pad "224" smd rect
			(at 2.050034 8.925052 270)
			(size 0.519938 1.4986)
			(layers "F.Cu" "F.Mask" "F.Paste")
			(net "GND")
		)
	)
)
